# T6G (Grand Teton) — schematic netlist excerpt (pin names and nets, part order shuffled) for the footprints in the layout excerpt that follows; sources: Cadence DE-HDL packaged netlist, KiCad conversion of 04192023_DAF0TMB3IC0_F0TG_MB_C_brd_V02_OCP.brd

R8166  Q_RES  33 5% CHIP  pkg 0402LF  page 210 : A = PWRGD_PVDDCR_SOC_P1 ; B = PWRGD_PVDDCR_SOC_P1_R
PR8003  Q_RES  2.2 1% CHIP  pkg 0402LF  page 269 : A = SW_P1V8_AUX_BT ; B = SW_P1V8_AUX_BT_R

(kicad_pcb
	(version 20260206)
	(generator "pcbnew")
	(generator_version "10.0")
	(general
		(thickness 1.6)
		(legacy_teardrops no)
	)
	(paper "A4")
	(title_block
		(title "04192023_DAF0TMB3IC0_F0TG_MB_C_brd_V02_OCP.brd")
		(comment 1 "Grand Teton / footprints 4523-4524 of 8354")
	)
	(layers
		(0 "F.Cu" signal "TOP")
		(4 "In1.Cu" signal "GND")
		(6 "In2.Cu" signal "IN1")
		(8 "In3.Cu" signal "GND1")
		(10 "In4.Cu" signal "IN2")
		(12 "In5.Cu" signal "GND2")
		(14 "In6.Cu" signal "IN3")
		(16 "In7.Cu" signal "GND3")
		(18 "In8.Cu" signal "VCC")
		(20 "In9.Cu" signal "VCC1")
		(22 "In10.Cu" signal "GND4")
		(24 "In11.Cu" signal "IN4")
		(26 "In12.Cu" signal "GND5")
		(28 "In13.Cu" signal "IN5")
		(30 "In14.Cu" signal "GND6")
		(32 "In15.Cu" signal "IN6")
		(34 "In16.Cu" signal "GND7")
		(2 "B.Cu" signal "BOTTOM")
		(9 "F.Adhes" user "F.Adhesive")
		(11 "B.Adhes" user "B.Adhesive")
		(13 "F.Paste" user "Package Geometry/Pastemask Top")
		(15 "B.Paste" user "Package Geometry/Pastemask Bottom")
		(5 "F.SilkS" user "Ref Des/Silkscreen Top")
		(7 "B.SilkS" user "Ref Des/Silkscreen Bottom")
		(1 "F.Mask" user "Board Geometry/Soldermask Top")
		(3 "B.Mask" user "Board Geometry/Soldermask Bottom")
		(17 "Dwgs.User" user "User.Drawings")
		(19 "Cmts.User" user "User.Comments")
		(21 "Eco1.User" user "User.Eco1")
		(23 "Eco2.User" user "User.Eco2")
		(25 "Edge.Cuts" user "Board Geometry/Outline")
		(27 "Margin" user)
		(31 "F.CrtYd" user "Package Geometry/Place Bound Top")
		(29 "B.CrtYd" user "Package Geometry/Place Bound Bottom")
		(35 "F.Fab" user "Ref Des/Assembly Top")
		(33 "B.Fab" user "Ref Des/Assembly Bottom")
	)
	(footprint ""
		(layer "F.Cu")
		(at 90.209878 -145.90141)
		(property "Reference" "R8166"
			(at 0 0 0)
			(layer "F.SilkS")
			(hide yes)
			(effects
				(font
					(size 1.27 1.27)
				)
			)
		)
		(property "Value" ""
			(at 0 0 0)
			(layer "F.Fab")
			(effects
				(font
					(size 1.27 1.27)
				)
			)
		)
		(duplicate_pad_numbers_are_jumpers no)
		(fp_line
			(start -0.7874 -0.4064)
			(end 0.7874 -0.4064)
			(stroke
				(width 0.1524)
				(type default)
			)
			(layer "F.SilkS")
		)
		(fp_line
			(start -0.7874 0.4064)
			(end -0.7874 -0.4064)
			(stroke
				(width 0.1524)
				(type default)
			)
			(layer "F.SilkS")
		)
		(fp_line
			(start 0.7874 -0.4064)
			(end 0.7874 0.4064)
			(stroke
				(width 0.1524)
				(type default)
			)
			(layer "F.SilkS")
		)
		(fp_line
			(start 0.7874 0.4064)
			(end -0.7874 0.4064)
			(stroke
				(width 0.1524)
				(type default)
			)
			(layer "F.SilkS")
		)
		(fp_line
			(start -0.67945 -0.305054)
			(end -0.12065 -0.305054)
			(stroke
				(width 0.1)
				(type default)
			)
			(layer "F.Fab")
		)
		(fp_line
			(start -0.67945 0.3048)
			(end -0.67945 -0.305054)
			(stroke
				(width 0.1)
				(type default)
			)
			(layer "F.Fab")
		)
		(fp_line
			(start -0.12065 -0.305054)
			(end -0.12065 -0.2794)
			(stroke
				(width 0.1)
				(type default)
			)
			(layer "F.Fab")
		)
		(fp_line
			(start -0.12065 -0.2794)
			(end 0.12065 -0.2794)
			(stroke
				(width 0.1)
				(type default)
			)
			(layer "F.Fab")
		)
		(fp_line
			(start -0.12065 0.2794)
			(end -0.12065 0.3048)
			(stroke
				(width 0.1)
				(type default)
			)
			(layer "F.Fab")
		)
		(fp_line
			(start -0.12065 0.3048)
			(end -0.67945 0.3048)
			(stroke
				(width 0.1)
				(type default)
			)
			(layer "F.Fab")
		)
		(fp_line
			(start 0.120396 0.2794)
			(end -0.12065 0.2794)
			(stroke
				(width 0.1)
				(type default)
			)
			(layer "F.Fab")
		)
		(fp_line
			(start 0.120396 0.3048)
			(end 0.120396 0.2794)
			(stroke
				(width 0.1)
				(type default)
			)
			(layer "F.Fab")
		)
		(fp_line
			(start 0.12065 -0.3048)
			(end 0.67945 -0.3048)
			(stroke
				(width 0.1)
				(type default)
			)
			(layer "F.Fab")
		)
		(fp_line
			(start 0.12065 -0.2794)
			(end 0.12065 -0.3048)
			(stroke
				(width 0.1)
				(type default)
			)
			(layer "F.Fab")
		)
		(fp_line
			(start 0.67945 -0.3048)
			(end 0.67945 0.3048)
			(stroke
				(width 0.1)
				(type default)
			)
			(layer "F.Fab")
		)
		(fp_line
			(start 0.67945 0.3048)
			(end 0.120396 0.3048)
			(stroke
				(width 0.1)
				(type default)
			)
			(layer "F.Fab")
		)
		(pad "1" smd circle
			(at -0.40005 0)
			(size 0 0)
			(layers "F.Cu" "F.Mask" "F.Paste")
			(net "PWRGD_PVDDCR_SOC_P1")
		)
		(pad "2" smd circle
			(at 0.40005 0)
			(size 0 0)
			(layers "F.Cu" "F.Mask" "F.Paste")
			(net "PWRGD_PVDDCR_SOC_P1_R")
		)
	)
	(footprint ""
		(layer "F.Cu")
		(at 146.194018 -76.877672 90)
		(property "Reference" "PR8003"
			(at 0 0 90)
			(layer "F.SilkS")
			(hide yes)
			(effects
				(font
					(size 1.27 1.27)
				)
			)
		)
		(property "Value" ""
			(at 0 0 90)
			(layer "F.Fab")
			(effects
				(font
					(size 1.27 1.27)
				)
			)
		)
		(duplicate_pad_numbers_are_jumpers no)
		(fp_line
			(start 0.7874 -0.4064)
			(end 0.7874 0.4064)
			(stroke
				(width 0.1524)
				(type default)
			)
			(layer "F.SilkS")
		)
		(fp_line
			(start -0.7874 -0.4064)
			(end 0.7874 -0.4064)
			(stroke
				(width 0.1524)
				(type default)
			)
			(layer "F.SilkS")
		)
		(fp_line
			(start 0.7874 0.4064)
			(end -0.7874 0.4064)
			(stroke
				(width 0.1524)
				(type default)
			)
			(layer "F.SilkS")
		)
		(fp_line
			(start -0.7874 0.4064)
			(end -0.7874 -0.4064)
			(stroke
				(width 0.1524)
				(type default)
			)
			(layer "F.SilkS")
		)
		(fp_line
			(start -0.12065 -0.305054)
			(end -0.12065 -0.2794)
			(stroke
				(width 0.1)
				(type default)
			)
			(layer "F.Fab")
		)
		(fp_line
			(start -0.67945 -0.305054)
			(end -0.12065 -0.305054)
			(stroke
				(width 0.1)
				(type default)
			)
			(layer "F.Fab")
		)
		(fp_line
			(start 0.67945 -0.3048)
			(end 0.67945 0.3048)
			(stroke
				(width 0.1)
				(type default)
			)
			(layer "F.Fab")
		)
		(fp_line
			(start 0.12065 -0.3048)
			(end 0.67945 -0.3048)
			(stroke
				(width 0.1)
				(type default)
			)
			(layer "F.Fab")
		)
		(fp_line
			(start 0.12065 -0.2794)
			(end 0.12065 -0.3048)
			(stroke
				(width 0.1)
				(type default)
			)
			(layer "F.Fab")
		)
		(fp_line
			(start -0.12065 -0.2794)
			(end 0.12065 -0.2794)
			(stroke
				(width 0.1)
				(type default)
			)
			(layer "F.Fab")
		)
		(fp_line
			(start 0.120396 0.2794)
			(end -0.12065 0.2794)
			(stroke
				(width 0.1)
				(type default)
			)
			(layer "F.Fab")
		)
		(fp_line
			(start -0.12065 0.2794)
			(end -0.12065 0.3048)
			(stroke
				(width 0.1)
				(type default)
			)
			(layer "F.Fab")
		)
		(fp_line
			(start 0.67945 0.3048)
			(end 0.120396 0.3048)
			(stroke
				(width 0.1)
				(type default)
			)
			(layer "F.Fab")
		)
		(fp_line
			(start 0.120396 0.3048)
			(end 0.120396 0.2794)
			(stroke
				(width 0.1)
				(type default)
			)
			(layer "F.Fab")
		)
		(fp_line
			(start -0.12065 0.3048)
			(end -0.67945 0.3048)
			(stroke
				(width 0.1)
				(type default)
			)
			(layer "F.Fab")
		)
		(fp_line
			(start -0.67945 0.3048)
			(end -0.67945 -0.305054)
			(stroke
				(width 0.1)
				(type default)
			)
			(layer "F.Fab")
		)
		(pad "1" smd circle
			(at -0.40005 0 90)
			(size 0 0)
			(layers "F.Cu" "F.Mask" "F.Paste")
			(net "SW_P1V8_AUX_BT")
		)
		(pad "2" smd circle
			(at 0.40005 0 90)
			(size 0 0)
			(layers "F.Cu" "F.Mask" "F.Paste")
			(net "SW_P1V8_AUX_BT_R")
		)
	)
)
